# Bryce Canyon_IOM_M2_Stackup.xlsx — Stack up_16342-2 (pcb-stackup)
|  |  |  |  |  |  | Version |  |  |  |  |  |  |  |  |  |  |  |  |  |  |  |  |  |  |  |
| Board Number: |  | 16342-2 |  |  |  | 02 |  |  |  |  |  |  |  |  |  |  |  |  |  |  |  |  |  |  |  |
| Project name: |  | Bryce Canyon |  |  |  |  |  |  |  |  |  |  |  |  |  |  |  |  |  |  |  |  |  |  |  |
| Model Name: |  | IOM_M.2 |  |  |  |  |  |  |  |  |  |  |  |  |  |  |  |  |  |  |  |  |  |  |  |
| Layer Count: |  | 8 Layer |  |  |  |  |  |  |  |  |  |  |  |  |  |  |  |  |  |  |  |  |  |  |  |
| Date: |  | 2017-09-25 00:00:00 |  |  |  |  |  |  |  |  |  |  |  |  |  |  |  |  |  |  |  |  |  |  |  |
| Loss Material: |  | NPG171+VLP/TU863+VLP  (Tg : 180/Td : 375) |  |  |  |  |  |  | Single Ended Type(mil) |  |  |  |  | Differential Type(mil) |  |  |  |  |  |  |  |  |  |  |  |
| Gold Finger(Y/N): |  | N |  |  |  |  |  | Imp | 50 |  |  |  | Imp | 85 |  |  |  |  |  | 100 |  |  |  |  |  |
| Customer: |  | <name> |  |  |  |  |  | Variation | Inner/Outer+/-5ohm |  |  |  | Variation | Inner/Outer+/-10% |  |  |  |  |  | Inner/Outer+/-10% |  |  |  |  |  |
| EE engineer |  | <name> |  |  |  |  |  | Bus | MISC./I2C |  |  |  | Bus | PCIe/Clock/USB |  |  |  |  |  | Clock/SATA |  |  |  |  |  |
| SI Engineer |  | <name> |  |  |  |  |  |  |  |  |  |  |  |  |  |  |  |  |  |  |  |  |  |  |  |
|  |  |  |  |  |  |  |  | Type | SE |  |  |  | Type | DP |  |  |  |  |  | DP |  |  |  |  |  |
| Layer |  |  | Thickness |  | Glass/Copper Style | Er | Df(1G) | Layers | 1,3,6,8 |  |  |  | Layers | 1,3,6,8 |  |  |  |  |  | 1,3,6,8 |  |  |  |  |  |
|  |  | Cu oz | Wiwynn |  |  | Wiwynn |  |  | Wiwynn |  |  |  |  | Wiwynn |  |  |  |  |  | Wiwynn |  |  |  |  |  |
|  | Mask |  | 0.5 |  |  | 3.4 | 0.025 |  | Width | Imp | Width | Imp |  | Width | Space | Imp | Width | Space | Imp | Width | Space | Imp | Width | Space | Imp |
| Top | Signal | 3/8 oz+plating | 1.7 |  |  |  |  | S1 | 5(L2) | 50.08 |  |  | S1 | 5.75(L2) | 6.5 | 85.36 |  |  |  | 4.9(L2) | 11.1 | 96.82 |  |  |  |
|  | Prepreg |  | 3 |  |  | 3.9 | 0.006 |  |  |  |  |  |  |  |  |  |  |  |  |  |  |  |  |  |  |
| L2 | GND | 1 oz | 1.3 |  |  |  |  | P2 | reference layer |  |  |  | P2 | reference layer |  |  |  |  |  | reference layer |  |  |  |  |  |
|  | Core |  | 4 |  |  | 3.9 | 0.006 |  |  |  |  |  |  |  |  |  |  |  |  |  |  |  |  |  |  |
| L3 | Signal | 1 oz | 1.3 |  |  |  |  | S3 | 5(L2/L4) | 49.28 |  |  | S3 | 5.5(L2/L4) | 7.5 | 84.9 |  |  |  | 4(L2/L4) | 8 | 97.59 |  |  |  |
|  | Prepreg |  | 16.4 |  |  | 4.2 | 0.006 |  |  |  |  |  |  |  |  |  |  |  |  |  |  |  |  |  |  |
| L4 | POWER | 1 oz | 1.3 |  |  |  |  | P4 | reference layer |  |  |  | P4 | reference layer |  |  |  |  |  | reference layer |  |  |  |  |  |
|  | Core |  | 4 |  |  | 3.8 | 0.006 |  |  |  |  |  |  |  |  |  |  |  |  |  |  |  |  |  |  |
| L5 | POWER | 1 oz | 1.3 | 0 | 0 |  |  | P5 | reference layer |  |  |  | P5 | reference layer |  |  |  |  |  | reference layer |  |  |  |  |  |
|  | Prepreg |  | 16.4 | 0 | 0 | 4.2 | 0.006 |  |  |  |  |  |  |  |  |  |  |  |  |  |  |  |  |  |  |
| L6 | Signal | 1 oz | 1.3 | 0 | 0 |  |  | S6 | 5(L5/L7) | 49.28 |  |  | S6 | 5.5(L5/L7) | 7.5 | 84.9 |  |  |  | 4(L5/L7) | 8 | 97.59 |  |  |  |
|  | Core |  | 4 | 0 | 0 | 3.9 | 0.006 |  |  |  |  |  |  |  |  |  |  |  |  |  |  |  |  |  |  |
| L7 | GND | 1 oz | 1.3 | 0 | 0 |  |  | P7 | reference layer |  |  |  | P7 | reference layer |  |  |  |  |  | reference layer |  |  |  |  |  |
|  | Prepreg |  | 3 | 0 | 0 | 3.9 | 0.006 |  |  |  |  |  |  |  |  |  |  |  |  |  |  |  |  |  |  |
| Bottom | Signal | 3/8 oz+plating | 1.7 | 0 | 0 |  |  | S8 | 5(L7) | 50.08 |  |  | S8 | 5.75(L7) | 6.5 | 85.36 |  |  |  | 4.9(L7) | 11.1 | 96.82 |  |  |  |
|  | Mask |  | 0.5 | 0 |  | 3.4 | 0.025 |  |  |  |  |  |  |  |  |  |  |  |  |  |  |  |  |  |  |
| Thickness requirement: 1.6 ± 10% mm |  | mil | 62.99999999999999 |  |  |  |  |  |  |  |  |  |  |  |  |  |  |  |  |  |  |  |  |  |  |
|  |  | mm | 1.6002032004064006 |  |  |  |  |  |  |  |  |  |  |  |  |  |  |  |  |  |  |  |  |  |  |
| Note: | 1. Unit is mil |  |  |  |  |  |  |  |  |  |  |  |  |  |  |  |  |  |  |  |  |  |  |  |  |
|  | 2. The total thickness includes trace and solder mask. |  |  |  |  |  |  |  |  |  |  |  |  |  |  |  |  |  |  |  |  |  |  |  |  |
|  | 3. Minimum hole copper thickness is 1.0 mil. |  |  |  |  |  |  |  |  |  |  |  |  |  |  |  |  |  |  |  |  |  |  |  |  |
|  | 4. Minimum surface copper thickness 1.5 mil. |  |  |  |  |  |  |  |  |  |  |  |  |  |  |  |  |  |  |  |  |  |  |  |  |
|  | 5. If there is no controlled impedance line described as the stackup in the gerber file, PCB supplier can ignore this kind of impedance control directly, but need to inform Wiwynn in engineering question(EQ). |  |  |  |  |  |  |  |  |  |  |  |  |  |  |  |  |  |  |  |  |  |  |  |  |
|  | 6. PCB test coupon requirement and PCB test note are described in the another sheets. |  |  |  |  |  |  |  |  |  |  |  |  |  |  |  |  |  |  |  |  |  |  |  |  |
|  | 7. If there is no "Delta-L" design in gerber file, PCB supplier should design 85 ohm "Delta-L" angle routing coupon and provide the measurement results in FAI report which meet the following criteria: |  |  |  |  |  |  |  |  |  |  |  |  |  |  |  |  |  |  |  |  |  |  |  |  |
|  | For middle-loss material | (Material: NPG171+VLP) |  |  |  |  |  |  |  |  |  |  |  |  |  |  |  |  |  |  |  |  |  |  |  |
|  | (1)   0.69 dB/inch @ 4GHz; 1.38 dB/inch @ 8GHz for microstrip routing |  |  |  |  |  |  |  |  |  |  |  |  |  |  |  |  |  |  |  |  |  |  |  |  |
|  | (2)   0.65 dB/inch @ 4GHz; 1.25 dB/inch @ 8GHz for stripline routing |  |  |  |  |  |  |  |  |  |  |  |  |  |  |  |  |  |  |  |  |  |  |  |  |
|  | For low-loss material | (Material: TU863+VLP) |  |  |  |  |  |  |  |  |  |  |  |  |  |  |  |  |  |  |  |  |  |  |  |
|  | (1)   0.55 dB/inch @ 4GHz; 1.05 dB/inch @ 8GHz for microstrip routing |  |  |  |  |  |  |  |  |  |  |  |  |  |  |  |  |  |  |  |  |  |  |  |  |
|  | (2)   0.48 dB/inch @ 4GHz; 0.9 dB/inch @ 8GHz for stripline routing |  |  |  |  |  |  |  |  |  |  |  |  |  |  |  |  |  |  |  |  |  |  |  |  |
